(kicad_pcb
	(version 20260206)
	(generator "pcbnew")
	(generator_version "10.0")
	(general
		(thickness 1.6)
		(legacy_teardrops no)
	)
	(paper "A4")
	(title_block
		(title "Bryce Canyon_F.DPB_16315-1-OCP.brd")
		(comment 1 "Bryce Canyon / footprint 1805 of 2223 (MONO4), pads 75-147 of 166")
	)
	(layers
		(0 "F.Cu" signal "TOP")
		(4 "In1.Cu" signal "L2GND")
		(6 "In2.Cu" signal "L3")
		(8 "In3.Cu" signal "L4GND")
		(10 "In4.Cu" signal "L5")
		(12 "In5.Cu" signal "L6VCC")
		(14 "In6.Cu" signal "L7VCC")
		(16 "In7.Cu" signal "L8")
		(18 "In8.Cu" signal "L9GND")
		(20 "In9.Cu" signal "L10")
		(22 "In10.Cu" signal "L11GND")
		(2 "B.Cu" signal "BOTTOM")
		(9 "F.Adhes" user "F.Adhesive")
		(11 "B.Adhes" user "B.Adhesive")
		(13 "F.Paste" user "Package Geometry/Pastemask Top")
		(15 "B.Paste" user "Package Geometry/Pastemask Bottom")
		(5 "F.SilkS" user "Ref Des/Silkscreen Top")
		(7 "B.SilkS" user "Ref Des/Silkscreen Bottom")
		(1 "F.Mask" user "Board Geometry/Soldermask Top")
		(3 "B.Mask" user "Board Geometry/Soldermask Bottom")
		(17 "Dwgs.User" user "User.Drawings")
		(19 "Cmts.User" user "User.Comments")
		(21 "Eco1.User" user "User.Eco1")
		(23 "Eco2.User" user "User.Eco2")
		(25 "Edge.Cuts" user "Board Geometry/Outline")
		(27 "Margin" user)
		(31 "F.CrtYd" user "Package Geometry/Place Bound Top")
		(29 "B.CrtYd" user "Package Geometry/Place Bound Bottom")
		(35 "F.Fab" user "Ref Des/Assembly Top")
		(33 "B.Fab" user "Ref Des/Assembly Bottom")
	)
	(footprint ""
		(layer "F.Cu")
		(at 281.999944 -14.85011 90)
		(property "Reference" "MONO4"
			(at 0 0 90)
			(layer "F.SilkS")
			(hide yes)
			(effects
				(font
					(size 1.27 1.27)
				)
			)
		)
		(property "Value" "AMP-CONN164-4R-1-GP"
			(at -25.705054 -1.203706 90)
			(unlocked yes)
			(layer "F.Fab")
			(hide yes)
			(effects
				(font
					(size 1.016 1.016)
					(thickness 0.1524)
				)
			)
		)
		(property "Device Type" "PREFIT-164P-890091-1H441"
			(at -25.705054 -2.727706 90)
			(unlocked yes)
			(layer "F.Fab")
			(hide yes)
			(effects
				(font
					(size 1.016 1.016)
					(thickness 0.1524)
				)
			)
		)
		(duplicate_pad_numbers_are_jumpers no)
		(pad "A73" thru_hole circle
			(at 62.349888 -1.249934 90)
			(size 1.0668 1.0668)
			(drill 0.719836)
			(layers "*.Cu" "*.Mask")
			(remove_unused_layers no)
			(net "PCIE_IOM_B_TO_COMP_B_22_DP")
			(clearance 0.1905)
			(thermal_gap 0.1905)
		)
		(pad "A74" thru_hole circle
			(at 63.349886 -3.24993 90)
			(size 1.0668 1.0668)
			(drill 0.719836)
			(layers "*.Cu" "*.Mask")
			(remove_unused_layers no)
			(net "PCIE_IOM_B_TO_COMP_B_22_DN")
			(clearance 0.1905)
			(thermal_gap 0.1905)
		)
		(pad "A75" thru_hole circle
			(at 64.349884 -1.249934 90)
			(size 1.0668 1.0668)
			(drill 0.719836)
			(layers "*.Cu" "*.Mask")
			(remove_unused_layers no)
			(net "GND")
			(clearance 0.1905)
			(thermal_gap 0.1905)
		)
		(pad "A76" thru_hole circle
			(at 65.349882 -3.24993 90)
			(size 1.0668 1.0668)
			(drill 0.719836)
			(layers "*.Cu" "*.Mask")
			(remove_unused_layers no)
			(net "GND")
			(clearance 0.1905)
			(thermal_gap 0.1905)
		)
		(pad "A77" thru_hole circle
			(at 66.34988 -1.249934 90)
			(size 1.0668 1.0668)
			(drill 0.719836)
			(layers "*.Cu" "*.Mask")
			(remove_unused_layers no)
			(net "PCIE_IOM_B_TO_COMP_B_23_DP")
			(clearance 0.1905)
			(thermal_gap 0.1905)
		)
		(pad "A78" thru_hole circle
			(at 67.349878 -3.24993 90)
			(size 1.0668 1.0668)
			(drill 0.719836)
			(layers "*.Cu" "*.Mask")
			(remove_unused_layers no)
			(net "PCIE_IOM_B_TO_COMP_B_23_DN")
			(clearance 0.1905)
			(thermal_gap 0.1905)
		)
		(pad "A79" thru_hole circle
			(at 68.349876 -1.249934 90)
			(size 1.0668 1.0668)
			(drill 0.719836)
			(layers "*.Cu" "*.Mask")
			(remove_unused_layers no)
			(net "GND")
			(clearance 0.1905)
			(thermal_gap 0.1905)
		)
		(pad "A80" thru_hole circle
			(at 69.349874 -3.24993 90)
			(size 1.0668 1.0668)
			(drill 0.719836)
			(layers "*.Cu" "*.Mask")
			(remove_unused_layers no)
			(net "GND")
			(clearance 0.1905)
			(thermal_gap 0.1905)
		)
		(pad "A81" thru_hole circle
			(at 70.350126 -1.249934 90)
			(size 1.0668 1.0668)
			(drill 0.719836)
			(layers "*.Cu" "*.Mask")
			(remove_unused_layers no)
			(net "P12V_B_COMP")
			(clearance 0.1905)
			(thermal_gap 0.1905)
		)
		(pad "A82" thru_hole circle
			(at 71.350124 -3.24993 90)
			(size 1.0668 1.0668)
			(drill 0.719836)
			(layers "*.Cu" "*.Mask")
			(remove_unused_layers no)
			(net "P12V_B_COMP")
			(clearance 0.1905)
			(thermal_gap 0.1905)
		)
		(pad "B1" thru_hole circle
			(at -11.649964 1.249934 90)
			(size 1.0668 1.0668)
			(drill 0.719836)
			(layers "*.Cu" "*.Mask")
			(remove_unused_layers no)
			(net "P12V_B_COMP")
			(clearance 0.1905)
			(thermal_gap 0.1905)
		)
		(pad "B2" thru_hole circle
			(at -10.649966 3.24993 90)
			(size 1.0668 1.0668)
			(drill 0.719836)
			(layers "*.Cu" "*.Mask")
			(remove_unused_layers no)
			(net "P12V_B_COMP")
			(clearance 0.1905)
			(thermal_gap 0.1905)
		)
		(pad "B3" thru_hole circle
			(at -9.649968 1.249934 90)
			(size 1.0668 1.0668)
			(drill 0.719836)
			(layers "*.Cu" "*.Mask")
			(remove_unused_layers no)
			(net "P12V_B_COMP")
			(clearance 0.1905)
			(thermal_gap 0.1905)
		)
		(pad "B4" thru_hole circle
			(at -8.64997 3.24993 90)
			(size 1.0668 1.0668)
			(drill 0.719836)
			(layers "*.Cu" "*.Mask")
			(remove_unused_layers no)
			(net "GND")
			(clearance 0.1905)
			(thermal_gap 0.1905)
		)
		(pad "B5" thru_hole circle
			(at -7.649972 1.249934 90)
			(size 1.0668 1.0668)
			(drill 0.719836)
			(layers "*.Cu" "*.Mask")
			(remove_unused_layers no)
			(net "TP_COMP_B_NCSI_TXEN")
			(clearance 0.1905)
			(thermal_gap 0.1905)
		)
		(pad "B6" thru_hole circle
			(at -6.649974 3.24993 90)
			(size 1.0668 1.0668)
			(drill 0.719836)
			(layers "*.Cu" "*.Mask")
			(remove_unused_layers no)
			(net "TP_COMP_B_NCSI_TXD0")
			(clearance 0.1905)
			(thermal_gap 0.1905)
		)
		(pad "B7" thru_hole circle
			(at -5.649976 1.249934 90)
			(size 1.0668 1.0668)
			(drill 0.719836)
			(layers "*.Cu" "*.Mask")
			(remove_unused_layers no)
			(net "TP_COMP_B_NCSI_TXD1")
			(clearance 0.1905)
			(thermal_gap 0.1905)
		)
		(pad "B8" thru_hole circle
			(at -4.649978 3.24993 90)
			(size 1.0668 1.0668)
			(drill 0.719836)
			(layers "*.Cu" "*.Mask")
			(remove_unused_layers no)
			(net "TP_COMP_B_NCSI_CRSDV")
			(clearance 0.1905)
			(thermal_gap 0.1905)
		)
		(pad "B9" thru_hole circle
			(at -3.64998 1.249934 90)
			(size 1.0668 1.0668)
			(drill 0.719836)
			(layers "*.Cu" "*.Mask")
			(remove_unused_layers no)
			(net "TP_COMP_B_NCSI_RXER")
			(clearance 0.1905)
			(thermal_gap 0.1905)
		)
		(pad "B10" thru_hole circle
			(at -2.649982 3.24993 90)
			(size 1.0668 1.0668)
			(drill 0.719836)
			(layers "*.Cu" "*.Mask")
			(remove_unused_layers no)
			(net "GND")
			(clearance 0.1905)
			(thermal_gap 0.1905)
		)
		(pad "B11" thru_hole circle
			(at -1.649984 1.249934 90)
			(size 1.0668 1.0668)
			(drill 0.719836)
			(layers "*.Cu" "*.Mask")
			(remove_unused_layers no)
			(net "PCIE_COMP_B_TO_IOM_B_RST_3")
			(clearance 0.1905)
			(thermal_gap 0.1905)
		)
		(pad "B12" thru_hole circle
			(at 1.35001 3.24993 90)
			(size 1.0668 1.0668)
			(drill 0.719836)
			(layers "*.Cu" "*.Mask")
			(remove_unused_layers no)
			(net "PCIE_COMP_B_TO_IOM_B_RST_4")
			(clearance 0.1905)
			(thermal_gap 0.1905)
		)
		(pad "B13" thru_hole circle
			(at 2.350008 1.249934 90)
			(size 1.0668 1.0668)
			(drill 0.719836)
			(layers "*.Cu" "*.Mask")
			(remove_unused_layers no)
			(net "PCIE_COMP_B_RST_5")
			(clearance 0.1905)
			(thermal_gap 0.1905)
		)
		(pad "B14" thru_hole circle
			(at 3.350006 3.24993 90)
			(size 1.0668 1.0668)
			(drill 0.719836)
			(layers "*.Cu" "*.Mask")
			(remove_unused_layers no)
			(net "GND")
			(clearance 0.1905)
			(thermal_gap 0.1905)
		)
		(pad "B15" thru_hole circle
			(at 4.350004 1.249934 90)
			(size 1.0668 1.0668)
			(drill 0.719836)
			(layers "*.Cu" "*.Mask")
			(remove_unused_layers no)
			(net "Net_1382")
			(clearance 0.1905)
			(thermal_gap 0.1905)
		)
		(pad "B16" thru_hole circle
			(at 5.350002 3.24993 90)
			(size 1.0668 1.0668)
			(drill 0.719836)
			(layers "*.Cu" "*.Mask")
			(remove_unused_layers no)
			(net "Net_1381")
			(clearance 0.1905)
			(thermal_gap 0.1905)
		)
		(pad "B17" thru_hole circle
			(at 6.35 1.249934 90)
			(size 1.0668 1.0668)
			(drill 0.719836)
			(layers "*.Cu" "*.Mask")
			(remove_unused_layers no)
			(net "GND")
			(clearance 0.1905)
			(thermal_gap 0.1905)
		)
		(pad "B18" thru_hole circle
			(at 7.349998 3.24993 90)
			(size 1.0668 1.0668)
			(drill 0.719836)
			(layers "*.Cu" "*.Mask")
			(remove_unused_layers no)
			(net "GND")
			(clearance 0.1905)
			(thermal_gap 0.1905)
		)
		(pad "B19" thru_hole circle
			(at 8.349996 1.249934 90)
			(size 1.0668 1.0668)
			(drill 0.719836)
			(layers "*.Cu" "*.Mask")
			(remove_unused_layers no)
			(net "Net_1377")
			(clearance 0.1905)
			(thermal_gap 0.1905)
		)
		(pad "B20" thru_hole circle
			(at 9.349994 3.24993 90)
			(size 1.0668 1.0668)
			(drill 0.719836)
			(layers "*.Cu" "*.Mask")
			(remove_unused_layers no)
			(net "Net_1380")
			(clearance 0.1905)
			(thermal_gap 0.1905)
		)
		(pad "B21" thru_hole circle
			(at 10.349992 1.249934 90)
			(size 1.0668 1.0668)
			(drill 0.719836)
			(layers "*.Cu" "*.Mask")
			(remove_unused_layers no)
			(net "GND")
			(clearance 0.1905)
			(thermal_gap 0.1905)
		)
		(pad "B22" thru_hole circle
			(at 11.34999 3.24993 90)
			(size 1.0668 1.0668)
			(drill 0.719836)
			(layers "*.Cu" "*.Mask")
			(remove_unused_layers no)
			(net "GND")
			(clearance 0.1905)
			(thermal_gap 0.1905)
		)
		(pad "B23" thru_hole circle
			(at 12.349988 1.249934 90)
			(size 1.0668 1.0668)
			(drill 0.719836)
			(layers "*.Cu" "*.Mask")
			(remove_unused_layers no)
			(net "Net_1373")
			(clearance 0.1905)
			(thermal_gap 0.1905)
		)
		(pad "B24" thru_hole circle
			(at 13.349986 3.24993 90)
			(size 1.0668 1.0668)
			(drill 0.719836)
			(layers "*.Cu" "*.Mask")
			(remove_unused_layers no)
			(net "Net_1375")
			(clearance 0.1905)
			(thermal_gap 0.1905)
		)
		(pad "B25" thru_hole circle
			(at 14.349984 1.249934 90)
			(size 1.0668 1.0668)
			(drill 0.719836)
			(layers "*.Cu" "*.Mask")
			(remove_unused_layers no)
			(net "GND")
			(clearance 0.1905)
			(thermal_gap 0.1905)
		)
		(pad "B26" thru_hole circle
			(at 15.349982 3.24993 90)
			(size 1.0668 1.0668)
			(drill 0.719836)
			(layers "*.Cu" "*.Mask")
			(remove_unused_layers no)
			(net "GND")
			(clearance 0.1905)
			(thermal_gap 0.1905)
		)
		(pad "B27" thru_hole circle
			(at 16.34998 1.249934 90)
			(size 1.0668 1.0668)
			(drill 0.719836)
			(layers "*.Cu" "*.Mask")
			(remove_unused_layers no)
			(net "Net_1372")
			(clearance 0.1905)
			(thermal_gap 0.1905)
		)
		(pad "B28" thru_hole circle
			(at 17.349978 3.24993 90)
			(size 1.0668 1.0668)
			(drill 0.719836)
			(layers "*.Cu" "*.Mask")
			(remove_unused_layers no)
			(net "Net_1369")
			(clearance 0.1905)
			(thermal_gap 0.1905)
		)
		(pad "B29" thru_hole circle
			(at 18.349976 1.249934 90)
			(size 1.0668 1.0668)
			(drill 0.719836)
			(layers "*.Cu" "*.Mask")
			(remove_unused_layers no)
			(net "GND")
			(clearance 0.1905)
			(thermal_gap 0.1905)
		)
		(pad "B30" thru_hole circle
			(at 19.349974 3.24993 90)
			(size 1.0668 1.0668)
			(drill 0.719836)
			(layers "*.Cu" "*.Mask")
			(remove_unused_layers no)
			(net "GND")
			(clearance 0.1905)
			(thermal_gap 0.1905)
		)
		(pad "B31" thru_hole circle
			(at 20.349972 1.249934 90)
			(size 1.0668 1.0668)
			(drill 0.719836)
			(layers "*.Cu" "*.Mask")
			(remove_unused_layers no)
			(net "PCIE_COMP_B_TO_IOM_B_CLK_3_DP")
			(clearance 0.1905)
			(thermal_gap 0.1905)
		)
		(pad "B32" thru_hole circle
			(at 21.34997 3.24993 90)
			(size 1.0668 1.0668)
			(drill 0.719836)
			(layers "*.Cu" "*.Mask")
			(remove_unused_layers no)
			(net "PCIE_COMP_B_TO_IOM_B_CLK_3_DN")
			(clearance 0.1905)
			(thermal_gap 0.1905)
		)
		(pad "B33" thru_hole circle
			(at 22.349968 1.249934 90)
			(size 1.0668 1.0668)
			(drill 0.719836)
			(layers "*.Cu" "*.Mask")
			(remove_unused_layers no)
			(net "GND")
			(clearance 0.1905)
			(thermal_gap 0.1905)
		)
		(pad "B34" thru_hole circle
			(at 23.349966 3.24993 90)
			(size 1.0668 1.0668)
			(drill 0.719836)
			(layers "*.Cu" "*.Mask")
			(remove_unused_layers no)
			(net "GND")
			(clearance 0.1905)
			(thermal_gap 0.1905)
		)
		(pad "B35" thru_hole circle
			(at 24.349964 1.249934 90)
			(size 1.0668 1.0668)
			(drill 0.719836)
			(layers "*.Cu" "*.Mask")
			(remove_unused_layers no)
			(net "PCIE_COMP_B_TO_IOM_B_12_DP")
			(clearance 0.1905)
			(thermal_gap 0.1905)
		)
		(pad "B36" thru_hole circle
			(at 25.349962 3.24993 90)
			(size 1.0668 1.0668)
			(drill 0.719836)
			(layers "*.Cu" "*.Mask")
			(remove_unused_layers no)
			(net "PCIE_COMP_B_TO_IOM_B_12_DN")
			(clearance 0.1905)
			(thermal_gap 0.1905)
		)
		(pad "B37" thru_hole circle
			(at 26.34996 1.249934 90)
			(size 1.0668 1.0668)
			(drill 0.719836)
			(layers "*.Cu" "*.Mask")
			(remove_unused_layers no)
			(net "GND")
			(clearance 0.1905)
			(thermal_gap 0.1905)
		)
		(pad "B38" thru_hole circle
			(at 27.349958 3.24993 90)
			(size 1.0668 1.0668)
			(drill 0.719836)
			(layers "*.Cu" "*.Mask")
			(remove_unused_layers no)
			(net "GND")
			(clearance 0.1905)
			(thermal_gap 0.1905)
		)
		(pad "B39" thru_hole circle
			(at 28.349956 1.249934 90)
			(size 1.0668 1.0668)
			(drill 0.719836)
			(layers "*.Cu" "*.Mask")
			(remove_unused_layers no)
			(net "PCIE_COMP_B_TO_IOM_B_13_DP")
			(clearance 0.1905)
			(thermal_gap 0.1905)
		)
		(pad "B40" thru_hole circle
			(at 29.349954 3.24993 90)
			(size 1.0668 1.0668)
			(drill 0.719836)
			(layers "*.Cu" "*.Mask")
			(remove_unused_layers no)
			(net "PCIE_COMP_B_TO_IOM_B_13_DN")
			(clearance 0.1905)
			(thermal_gap 0.1905)
		)
		(pad "B41" thru_hole circle
			(at 30.349952 1.249934 90)
			(size 1.0668 1.0668)
			(drill 0.719836)
			(layers "*.Cu" "*.Mask")
			(remove_unused_layers no)
			(net "GND")
			(clearance 0.1905)
			(thermal_gap 0.1905)
		)
		(pad "B42" thru_hole circle
			(at 31.34995 3.24993 90)
			(size 1.0668 1.0668)
			(drill 0.719836)
			(layers "*.Cu" "*.Mask")
			(remove_unused_layers no)
			(net "GND")
			(clearance 0.1905)
			(thermal_gap 0.1905)
		)
		(pad "B43" thru_hole circle
			(at 32.349948 1.249934 90)
			(size 1.0668 1.0668)
			(drill 0.719836)
			(layers "*.Cu" "*.Mask")
			(remove_unused_layers no)
			(net "PCIE_COMP_B_TO_IOM_B_14_DP")
			(clearance 0.1905)
			(thermal_gap 0.1905)
		)
		(pad "B44" thru_hole circle
			(at 33.349946 3.24993 90)
			(size 1.0668 1.0668)
			(drill 0.719836)
			(layers "*.Cu" "*.Mask")
			(remove_unused_layers no)
			(net "PCIE_COMP_B_TO_IOM_B_14_DN")
			(clearance 0.1905)
			(thermal_gap 0.1905)
		)
		(pad "B45" thru_hole circle
			(at 34.349944 1.249934 90)
			(size 1.0668 1.0668)
			(drill 0.719836)
			(layers "*.Cu" "*.Mask")
			(remove_unused_layers no)
			(net "GND")
			(clearance 0.1905)
			(thermal_gap 0.1905)
		)
		(pad "B46" thru_hole circle
			(at 35.349942 3.24993 90)
			(size 1.0668 1.0668)
			(drill 0.719836)
			(layers "*.Cu" "*.Mask")
			(remove_unused_layers no)
			(net "GND")
			(clearance 0.1905)
			(thermal_gap 0.1905)
		)
		(pad "B47" thru_hole circle
			(at 36.34994 1.249934 90)
			(size 1.0668 1.0668)
			(drill 0.719836)
			(layers "*.Cu" "*.Mask")
			(remove_unused_layers no)
			(net "PCIE_COMP_B_TO_IOM_B_15_DP")
			(clearance 0.1905)
			(thermal_gap 0.1905)
		)
		(pad "B48" thru_hole circle
			(at 37.349938 3.24993 90)
			(size 1.0668 1.0668)
			(drill 0.719836)
			(layers "*.Cu" "*.Mask")
			(remove_unused_layers no)
			(net "PCIE_COMP_B_TO_IOM_B_15_DN")
			(clearance 0.1905)
			(thermal_gap 0.1905)
		)
		(pad "B49" thru_hole circle
			(at 38.349936 1.249934 90)
			(size 1.0668 1.0668)
			(drill 0.719836)
			(layers "*.Cu" "*.Mask")
			(remove_unused_layers no)
			(net "GND")
			(clearance 0.1905)
			(thermal_gap 0.1905)
		)
		(pad "B50" thru_hole circle
			(at 39.349934 3.24993 90)
			(size 1.0668 1.0668)
			(drill 0.719836)
			(layers "*.Cu" "*.Mask")
			(remove_unused_layers no)
			(net "GND")
			(clearance 0.1905)
			(thermal_gap 0.1905)
		)
		(pad "B51" thru_hole circle
			(at 40.349932 1.249934 90)
			(size 1.0668 1.0668)
			(drill 0.719836)
			(layers "*.Cu" "*.Mask")
			(remove_unused_layers no)
			(net "PCIE_COMP_B_TO_IOM_B_16_DP")
			(clearance 0.1905)
			(thermal_gap 0.1905)
		)
		(pad "B52" thru_hole circle
			(at 41.34993 3.24993 90)
			(size 1.0668 1.0668)
			(drill 0.719836)
			(layers "*.Cu" "*.Mask")
			(remove_unused_layers no)
			(net "PCIE_COMP_B_TO_IOM_B_16_DN")
			(clearance 0.1905)
			(thermal_gap 0.1905)
		)
		(pad "B53" thru_hole circle
			(at 42.349928 1.249934 90)
			(size 1.0668 1.0668)
			(drill 0.719836)
			(layers "*.Cu" "*.Mask")
			(remove_unused_layers no)
			(net "GND")
			(clearance 0.1905)
			(thermal_gap 0.1905)
		)
		(pad "B54" thru_hole circle
			(at 43.349926 3.24993 90)
			(size 1.0668 1.0668)
			(drill 0.719836)
			(layers "*.Cu" "*.Mask")
			(remove_unused_layers no)
			(net "GND")
			(clearance 0.1905)
			(thermal_gap 0.1905)
		)
		(pad "B55" thru_hole circle
			(at 44.349924 1.249934 90)
			(size 1.0668 1.0668)
			(drill 0.719836)
			(layers "*.Cu" "*.Mask")
			(remove_unused_layers no)
			(net "PCIE_COMP_B_TO_IOM_B_17_DP")
			(clearance 0.1905)
			(thermal_gap 0.1905)
		)
		(pad "B56" thru_hole circle
			(at 45.349922 3.24993 90)
			(size 1.0668 1.0668)
			(drill 0.719836)
			(layers "*.Cu" "*.Mask")
			(remove_unused_layers no)
			(net "PCIE_COMP_B_TO_IOM_B_17_DN")
			(clearance 0.1905)
			(thermal_gap 0.1905)
		)
		(pad "B57" thru_hole circle
			(at 46.34992 1.249934 90)
			(size 1.0668 1.0668)
			(drill 0.719836)
			(layers "*.Cu" "*.Mask")
			(remove_unused_layers no)
			(net "GND")
			(clearance 0.1905)
			(thermal_gap 0.1905)
		)
		(pad "B58" thru_hole circle
			(at 47.349918 3.24993 90)
			(size 1.0668 1.0668)
			(drill 0.719836)
			(layers "*.Cu" "*.Mask")
			(remove_unused_layers no)
			(net "GND")
			(clearance 0.1905)
			(thermal_gap 0.1905)
		)
		(pad "B59" thru_hole circle
			(at 48.349916 1.249934 90)
			(size 1.0668 1.0668)
			(drill 0.719836)
			(layers "*.Cu" "*.Mask")
			(remove_unused_layers no)
			(net "PCIE_COMP_B_TO_IOM_B_18_DP")
			(clearance 0.1905)
			(thermal_gap 0.1905)
		)
		(pad "B60" thru_hole circle
			(at 49.349914 3.24993 90)
			(size 1.0668 1.0668)
			(drill 0.719836)
			(layers "*.Cu" "*.Mask")
			(remove_unused_layers no)
			(net "PCIE_COMP_B_TO_IOM_B_18_DN")
			(clearance 0.1905)
			(thermal_gap 0.1905)
		)
		(pad "B61" thru_hole circle
			(at 50.349912 1.249934 90)
			(size 1.0668 1.0668)
			(drill 0.719836)
			(layers "*.Cu" "*.Mask")
			(remove_unused_layers no)
			(net "GND")
			(clearance 0.1905)
			(thermal_gap 0.1905)
		)
		(pad "B62" thru_hole circle
			(at 51.34991 3.24993 90)
			(size 1.0668 1.0668)
			(drill 0.719836)
			(layers "*.Cu" "*.Mask")
			(remove_unused_layers no)
			(net "GND")
			(clearance 0.1905)
			(thermal_gap 0.1905)
		)
		(pad "B63" thru_hole circle
			(at 52.349908 1.249934 90)
			(size 1.0668 1.0668)
			(drill 0.719836)
			(layers "*.Cu" "*.Mask")
			(remove_unused_layers no)
			(net "PCIE_COMP_B_TO_IOM_B_19_DP")
			(clearance 0.1905)
			(thermal_gap 0.1905)
		)
	)
)
